M48
INCH,TZ
T01C.01
T02C.012
T03C.016
T04C.028
T05C.032
T06C.036
T07C.052
T08C.086
T09C.091
T010C.224
;EXTENTS: -100.000 -100.000 200.000 200.000 
;LEADER: 12 
;HEADER: 
;CODE  : ASCII 
;FILE  : 16369-sd.rou for board 16369-sd.brd
%
G90
F1
M16
G40
M30
